# TIMECARD (Time Appliance Project (Time Card)) — schematic netlist excerpt (pin names and nets, part order shuffled) for the footprints in the layout excerpt that follows; sources: Cadence DE-HDL packaged netlist, KiCad conversion of R4006-B0001-02_R01.brd

R357  RESISTOR  0OHM -  pkg SMC_0805R_H026  page 21 : \1\ = XP5R0V_MAC ; \2\ = UNNAMED_527_FUSE_I244_1
C263  CAPACITOR  4700PF 25V 10%  pkg SMC_0201R  page 29 : \1\ = UNNAMED_523_CAPACITOR_I9_1 ; \2\ = XP1R0V_AGND

(kicad_pcb
	(version 20260206)
	(generator "pcbnew")
	(generator_version "10.0")
	(general
		(thickness 1.6)
		(legacy_teardrops no)
	)
	(paper "A4")
	(title_block
		(title "timecard-production-celestica-r4006 — R4006-B0001-02_R01.brd")
		(comment 1 "Time Appliance Project (Time Card) / footprints 710-711 of 1113")
	)
	(layers
		(0 "F.Cu" signal "TOP")
		(4 "In1.Cu" signal "L02_GND1")
		(6 "In2.Cu" signal "L03_SIG1")
		(8 "In3.Cu" signal "L04_GND2")
		(10 "In4.Cu" signal "L05_VCC1")
		(12 "In5.Cu" signal "L06_VCC2")
		(14 "In6.Cu" signal "L07_GND3")
		(16 "In7.Cu" signal "L08_SIG2")
		(18 "In8.Cu" signal "L09_GND4")
		(2 "B.Cu" signal "BOTTOM")
		(9 "F.Adhes" user "F.Adhesive")
		(11 "B.Adhes" user "B.Adhesive")
		(13 "F.Paste" user "Package Geometry/Pastemask Top")
		(15 "B.Paste" user "Package Geometry/Pastemask Bottom")
		(5 "F.SilkS" user "Ref Des/Silkscreen Top")
		(7 "B.SilkS" user "Ref Des/Silkscreen Bottom")
		(1 "F.Mask" user "Board Geometry/Soldermask Top")
		(3 "B.Mask" user "Board Geometry/Soldermask Bottom")
		(17 "Dwgs.User" user "User.Drawings")
		(19 "Cmts.User" user "User.Comments")
		(21 "Eco1.User" user "User.Eco1")
		(23 "Eco2.User" user "User.Eco2")
		(25 "Edge.Cuts" user "Board Geometry/Outline")
		(27 "Margin" user)
		(31 "F.CrtYd" user "Package Geometry/Place Bound Top")
		(29 "B.CrtYd" user "Package Geometry/Place Bound Bottom")
		(35 "F.Fab" user "Ref Des/Assembly Top")
		(33 "B.Fab" user "Ref Des/Assembly Bottom")
	)
	(footprint ""
		(layer "B.Cu")
		(at 72.39 -58.674 90)
		(property "Reference" "R357"
			(at 3.175 7.32663 270)
			(unlocked yes)
			(layer "B.SilkS")
			(effects
				(font
					(size 0.7874 0.5842)
					(thickness 0.1524)
				)
				(justify mirror)
			)
		)
		(property "Value" "VAL*"
			(at -0.0508 3.159506 90)
			(unlocked yes)
			(layer "B.Fab")
			(hide yes)
			(effects
				(font
					(size 0.7874 0.5842)
					(thickness 0.1524)
				)
				(justify mirror)
			)
		)
		(property "Tolerance" "TOL*"
			(at -0.0508 4.124706 90)
			(unlocked yes)
			(layer "Cmts.User")
			(hide yes)
			(effects
				(font
					(size 0.7874 0.5842)
					(thickness 0.1524)
				)
				(justify mirror)
			)
		)
		(property "User Part Number" "PARTNUM*"
			(at -0.0508 5.089906 90)
			(unlocked yes)
			(layer "Cmts.User")
			(hide yes)
			(effects
				(font
					(size 0.7874 0.5842)
					(thickness 0.1524)
				)
				(justify mirror)
			)
		)
		(property "Device Type" "RESISTOR-G157-100R0-J0,0OHM,-"
			(at 0 2.194306 90)
			(unlocked yes)
			(layer "B.Fab")
			(hide yes)
			(effects
				(font
					(size 0.7874 0.5842)
					(thickness 0.1524)
				)
				(justify mirror)
			)
		)
		(duplicate_pad_numbers_are_jumpers no)
		(fp_line
			(start 1.5748 -0.9398)
			(end 1.5748 0.9398)
			(stroke
				(width 0.1)
				(type default)
			)
			(layer "B.SilkS")
		)
		(fp_line
			(start -1.5748 -0.9398)
			(end 1.5748 -0.9398)
			(stroke
				(width 0.1)
				(type default)
			)
			(layer "B.SilkS")
		)
		(fp_line
			(start 1.5748 0.9398)
			(end -1.5748 0.9398)
			(stroke
				(width 0.1)
				(type default)
			)
			(layer "B.SilkS")
		)
		(fp_line
			(start -1.5748 0.9398)
			(end -1.5748 -0.9398)
			(stroke
				(width 0.1)
				(type default)
			)
			(layer "B.SilkS")
		)
		(fp_rect
			(start 1.5748 0.9398)
			(end -1.5748 -0.9398)
			(stroke
				(width 0)
				(type default)
			)
			(fill no)
			(layer "B.CrtYd")
		)
		(fp_line
			(start 1.016 -0.635)
			(end 1.016 0.635)
			(stroke
				(width 0.1)
				(type default)
			)
			(layer "B.Fab")
		)
		(fp_line
			(start -1.016 -0.635)
			(end 1.016 -0.635)
			(stroke
				(width 0.1)
				(type default)
			)
			(layer "B.Fab")
		)
		(fp_line
			(start 1.016 0.635)
			(end -1.016 0.635)
			(stroke
				(width 0.1)
				(type default)
			)
			(layer "B.Fab")
		)
		(fp_line
			(start -1.016 0.635)
			(end -1.016 -0.635)
			(stroke
				(width 0.1)
				(type default)
			)
			(layer "B.Fab")
		)
		(pad "1" smd rect
			(at 0.8382 0 270)
			(size 0.9652 1.3716)
			(layers "B.Cu" "B.Mask" "B.Paste")
			(net "XP5R0V_MAC")
		)
		(pad "2" smd rect
			(at -0.8382 0 270)
			(size 0.9652 1.3716)
			(layers "B.Cu" "B.Mask" "B.Paste")
			(net "UNNAMED_527_FUSE_I244_1")
		)
		(zone
			(layer "B.Cu")
			(hatch none 0.5)
			(connect_pads
				(clearance 0)
			)
			(min_thickness 0.25)
			(keepout
				(tracks not_allowed)
				(vias allowed)
				(pads allowed)
				(copperpour not_allowed)
				(footprints allowed)
			)
			(placement
				(enabled no)
				(sheetname "")
			)
			(fill
				(thermal_gap 0.5)
				(thermal_bridge_width 0.5)
				(island_removal_mode 0)
			)
			(polygon
				(pts
					(xy 73.025 -58.9026) (xy 71.755 -58.9026) (xy 71.755 -58.4454) (xy 73.025 -58.4454)
				)
			)
		)
		(zone
			(layer "B.Cu")
			(hatch none 0.5)
			(connect_pads
				(clearance 0)
			)
			(min_thickness 0.25)
			(keepout
				(tracks allowed)
				(vias not_allowed)
				(pads allowed)
				(copperpour not_allowed)
				(footprints allowed)
			)
			(placement
				(enabled no)
				(sheetname "")
			)
			(fill
				(thermal_gap 0.5)
				(thermal_bridge_width 0.5)
				(island_removal_mode 0)
			)
			(polygon
				(pts
					(xy 73.025 -58.9026) (xy 71.755 -58.9026) (xy 71.755 -58.4454) (xy 73.025 -58.4454)
				)
			)
		)
	)
	(footprint ""
		(layer "B.Cu")
		(at 143.383 -59.563 90)
		(property "Reference" "C263"
			(at 3.429 0.08763 270)
			(unlocked yes)
			(layer "B.SilkS")
			(effects
				(font
					(size 0.7874 0.5842)
					(thickness 0.1524)
				)
				(justify mirror)
			)
		)
		(property "Value" "VAL*"
			(at -0.193548 2.13614 90)
			(unlocked yes)
			(layer "B.Fab")
			(hide yes)
			(effects
				(font
					(size 0.7874 0.5842)
					(thickness 0.1524)
				)
				(justify mirror)
			)
		)
		(property "User Part Number" "PARTNUM*"
			(at -0.216154 4.185666 90)
			(unlocked yes)
			(layer "Cmts.User")
			(hide yes)
			(effects
				(font
					(size 0.7874 0.5842)
					(thickness 0.1524)
				)
				(justify mirror)
			)
		)
		(property "Device Type" "CAPACITOR-G104-0B472-EK,4700PFA"
			(at -0.184404 1.180592 90)
			(unlocked yes)
			(layer "B.Fab")
			(hide yes)
			(effects
				(font
					(size 0.7874 0.5842)
					(thickness 0.1524)
				)
				(justify mirror)
			)
		)
		(property "Tolerance" "TOL*"
			(at -0.216154 3.1496 90)
			(unlocked yes)
			(layer "Cmts.User")
			(hide yes)
			(effects
				(font
					(size 0.7874 0.5842)
					(thickness 0.1524)
				)
				(justify mirror)
			)
		)
		(duplicate_pad_numbers_are_jumpers no)
		(fp_line
			(start 0.671322 -0.4445)
			(end -0.671322 -0.4445)
			(stroke
				(width 0.1)
				(type default)
			)
			(layer "B.SilkS")
		)
		(fp_line
			(start -0.671322 -0.4445)
			(end -0.671322 0.4445)
			(stroke
				(width 0.1)
				(type default)
			)
			(layer "B.SilkS")
		)
		(fp_line
			(start 0.671322 0.4445)
			(end 0.671322 -0.4445)
			(stroke
				(width 0.1)
				(type default)
			)
			(layer "B.SilkS")
		)
		(fp_line
			(start -0.671322 0.4445)
			(end 0.671322 0.4445)
			(stroke
				(width 0.1)
				(type default)
			)
			(layer "B.SilkS")
		)
		(fp_rect
			(start 0.671322 0.4445)
			(end -0.671322 -0.4445)
			(stroke
				(width 0)
				(type default)
			)
			(fill no)
			(layer "B.CrtYd")
		)
		(fp_line
			(start 0.31496 -0.1651)
			(end 0.31496 0.1651)
			(stroke
				(width 0.1)
				(type default)
			)
			(layer "B.Fab")
		)
		(fp_line
			(start -0.31496 -0.1651)
			(end 0.31496 -0.1651)
			(stroke
				(width 0.1)
				(type default)
			)
			(layer "B.Fab")
		)
		(fp_line
			(start 0.31496 0.1651)
			(end -0.31496 0.1651)
			(stroke
				(width 0.1)
				(type default)
			)
			(layer "B.Fab")
		)
		(fp_line
			(start -0.31496 0.1651)
			(end -0.31496 -0.1651)
			(stroke
				(width 0.1)
				(type default)
			)
			(layer "B.Fab")
		)
		(pad "1" smd rect
			(at 0.264922 0 270)
			(size 0.3048 0.381)
			(layers "B.Cu" "B.Mask" "B.Paste")
			(net "UNNAMED_523_CAPACITOR_I9_1")
		)
		(pad "2" smd rect
			(at -0.264922 0 270)
			(size 0.3048 0.381)
			(layers "B.Cu" "B.Mask" "B.Paste")
			(net "XP1R0V_AGND")
		)
		(zone
			(layer "B.Cu")
			(hatch none 0.5)
			(connect_pads
				(clearance 0)
			)
			(min_thickness 0.25)
			(keepout
				(tracks allowed)
				(vias not_allowed)
				(pads allowed)
				(copperpour not_allowed)
				(footprints allowed)
			)
			(placement
				(enabled no)
				(sheetname "")
			)
			(fill
				(thermal_gap 0.5)
				(thermal_bridge_width 0.5)
				(island_removal_mode 0)
			)
			(polygon
				(pts
					(xy 143.1925 -59.675522) (xy 143.5735 -59.675522) (xy 143.5735 -59.450478) (xy 143.1925 -59.450478)
				)
			)
		)
		(zone
			(layer "B.Cu")
			(hatch none 0.5)
			(connect_pads
				(clearance 0)
			)
			(min_thickness 0.25)
			(keepout
				(tracks not_allowed)
				(vias allowed)
				(pads allowed)
				(copperpour not_allowed)
				(footprints allowed)
			)
			(placement
				(enabled no)
				(sheetname "")
			)
			(fill
				(thermal_gap 0.5)
				(thermal_bridge_width 0.5)
				(island_removal_mode 0)
			)
			(polygon
				(pts
					(xy 143.5735 -59.675522) (xy 143.5735 -59.450478) (xy 143.1925 -59.450478) (xy 143.1925 -59.675522)
				)
			)
		)
	)
)
